# T6G (Grand Teton) — schematic netlist excerpt (pin names and nets, part order shuffled) for the footprints in the layout excerpt that follows; sources: Cadence DE-HDL packaged netlist, KiCad conversion of 04192023_DAF0TMB3IC0_F0TG_MB_C_brd_V02_OCP.brd

PR37  Q_RES  0 5% CHIP  pkg 0402LF  page 207 : A = NC_PVDD11_S3_P0_IMON3 ; B = GND
R3235  Q_RES  100K 1% CHIP  pkg 0402LF  page 139 : A = RST_HP_OCP_V3_2_R_N ; B = GND

(kicad_pcb
	(version 20260206)
	(generator "pcbnew")
	(generator_version "10.0")
	(general
		(thickness 1.6)
		(legacy_teardrops no)
	)
	(paper "A4")
	(title_block
		(title "04192023_DAF0TMB3IC0_F0TG_MB_C_brd_V02_OCP.brd")
		(comment 1 "Grand Teton / footprints 2370-2371 of 8354")
	)
	(layers
		(0 "F.Cu" signal "TOP")
		(4 "In1.Cu" signal "GND")
		(6 "In2.Cu" signal "IN1")
		(8 "In3.Cu" signal "GND1")
		(10 "In4.Cu" signal "IN2")
		(12 "In5.Cu" signal "GND2")
		(14 "In6.Cu" signal "IN3")
		(16 "In7.Cu" signal "GND3")
		(18 "In8.Cu" signal "VCC")
		(20 "In9.Cu" signal "VCC1")
		(22 "In10.Cu" signal "GND4")
		(24 "In11.Cu" signal "IN4")
		(26 "In12.Cu" signal "GND5")
		(28 "In13.Cu" signal "IN5")
		(30 "In14.Cu" signal "GND6")
		(32 "In15.Cu" signal "IN6")
		(34 "In16.Cu" signal "GND7")
		(2 "B.Cu" signal "BOTTOM")
		(9 "F.Adhes" user "F.Adhesive")
		(11 "B.Adhes" user "B.Adhesive")
		(13 "F.Paste" user "Package Geometry/Pastemask Top")
		(15 "B.Paste" user "Package Geometry/Pastemask Bottom")
		(5 "F.SilkS" user "Ref Des/Silkscreen Top")
		(7 "B.SilkS" user "Ref Des/Silkscreen Bottom")
		(1 "F.Mask" user "Board Geometry/Soldermask Top")
		(3 "B.Mask" user "Board Geometry/Soldermask Bottom")
		(17 "Dwgs.User" user "User.Drawings")
		(19 "Cmts.User" user "User.Comments")
		(21 "Eco1.User" user "User.Eco1")
		(23 "Eco2.User" user "User.Eco2")
		(25 "Edge.Cuts" user "Board Geometry/Outline")
		(27 "Margin" user)
		(31 "F.CrtYd" user "Package Geometry/Place Bound Top")
		(29 "B.CrtYd" user "Package Geometry/Place Bound Bottom")
		(35 "F.Fab" user "Ref Des/Assembly Top")
		(33 "B.Fab" user "Ref Des/Assembly Bottom")
	)
	(footprint ""
		(layer "F.Cu")
		(at 56.50992 -31.664148)
		(property "Reference" "R3235"
			(at 0 0 0)
			(layer "F.SilkS")
			(hide yes)
			(effects
				(font
					(size 1.27 1.27)
				)
			)
		)
		(property "Value" ""
			(at 0 0 0)
			(layer "F.Fab")
			(effects
				(font
					(size 1.27 1.27)
				)
			)
		)
		(duplicate_pad_numbers_are_jumpers no)
		(fp_line
			(start -0.7874 -0.4064)
			(end 0.7874 -0.4064)
			(stroke
				(width 0.1524)
				(type default)
			)
			(layer "F.SilkS")
		)
		(fp_line
			(start -0.7874 0.4064)
			(end -0.7874 -0.4064)
			(stroke
				(width 0.1524)
				(type default)
			)
			(layer "F.SilkS")
		)
		(fp_line
			(start 0.7874 -0.4064)
			(end 0.7874 0.4064)
			(stroke
				(width 0.1524)
				(type default)
			)
			(layer "F.SilkS")
		)
		(fp_line
			(start 0.7874 0.4064)
			(end -0.7874 0.4064)
			(stroke
				(width 0.1524)
				(type default)
			)
			(layer "F.SilkS")
		)
		(fp_line
			(start -0.67945 -0.305054)
			(end -0.12065 -0.305054)
			(stroke
				(width 0.1)
				(type default)
			)
			(layer "F.Fab")
		)
		(fp_line
			(start -0.67945 0.3048)
			(end -0.67945 -0.305054)
			(stroke
				(width 0.1)
				(type default)
			)
			(layer "F.Fab")
		)
		(fp_line
			(start -0.12065 -0.305054)
			(end -0.12065 -0.2794)
			(stroke
				(width 0.1)
				(type default)
			)
			(layer "F.Fab")
		)
		(fp_line
			(start -0.12065 -0.2794)
			(end 0.12065 -0.2794)
			(stroke
				(width 0.1)
				(type default)
			)
			(layer "F.Fab")
		)
		(fp_line
			(start -0.12065 0.2794)
			(end -0.12065 0.3048)
			(stroke
				(width 0.1)
				(type default)
			)
			(layer "F.Fab")
		)
		(fp_line
			(start -0.12065 0.3048)
			(end -0.67945 0.3048)
			(stroke
				(width 0.1)
				(type default)
			)
			(layer "F.Fab")
		)
		(fp_line
			(start 0.120396 0.2794)
			(end -0.12065 0.2794)
			(stroke
				(width 0.1)
				(type default)
			)
			(layer "F.Fab")
		)
		(fp_line
			(start 0.120396 0.3048)
			(end 0.120396 0.2794)
			(stroke
				(width 0.1)
				(type default)
			)
			(layer "F.Fab")
		)
		(fp_line
			(start 0.12065 -0.3048)
			(end 0.67945 -0.3048)
			(stroke
				(width 0.1)
				(type default)
			)
			(layer "F.Fab")
		)
		(fp_line
			(start 0.12065 -0.2794)
			(end 0.12065 -0.3048)
			(stroke
				(width 0.1)
				(type default)
			)
			(layer "F.Fab")
		)
		(fp_line
			(start 0.67945 -0.3048)
			(end 0.67945 0.3048)
			(stroke
				(width 0.1)
				(type default)
			)
			(layer "F.Fab")
		)
		(fp_line
			(start 0.67945 0.3048)
			(end 0.120396 0.3048)
			(stroke
				(width 0.1)
				(type default)
			)
			(layer "F.Fab")
		)
		(pad "1" smd circle
			(at -0.40005 0)
			(size 0 0)
			(layers "F.Cu" "F.Mask" "F.Paste")
			(net "RST_HP_OCP_V3_2_R_N")
		)
		(pad "2" smd circle
			(at 0.40005 0)
			(size 0 0)
			(layers "F.Cu" "F.Mask" "F.Paste")
			(net "GND")
		)
	)
	(footprint ""
		(layer "F.Cu")
		(at 418.852096 -357.688134 -90)
		(property "Reference" "PR37"
			(at 0 0 270)
			(layer "F.SilkS")
			(hide yes)
			(effects
				(font
					(size 1.27 1.27)
				)
			)
		)
		(property "Value" ""
			(at 0 0 270)
			(layer "F.Fab")
			(effects
				(font
					(size 1.27 1.27)
				)
			)
		)
		(duplicate_pad_numbers_are_jumpers no)
		(fp_line
			(start -0.7874 0.4064)
			(end -0.7874 -0.4064)
			(stroke
				(width 0.1524)
				(type default)
			)
			(layer "F.SilkS")
		)
		(fp_line
			(start 0.7874 0.4064)
			(end -0.7874 0.4064)
			(stroke
				(width 0.1524)
				(type default)
			)
			(layer "F.SilkS")
		)
		(fp_line
			(start -0.7874 -0.4064)
			(end 0.7874 -0.4064)
			(stroke
				(width 0.1524)
				(type default)
			)
			(layer "F.SilkS")
		)
		(fp_line
			(start 0.7874 -0.4064)
			(end 0.7874 0.4064)
			(stroke
				(width 0.1524)
				(type default)
			)
			(layer "F.SilkS")
		)
		(fp_line
			(start -0.67945 0.3048)
			(end -0.67945 -0.305054)
			(stroke
				(width 0.1)
				(type default)
			)
			(layer "F.Fab")
		)
		(fp_line
			(start -0.12065 0.3048)
			(end -0.67945 0.3048)
			(stroke
				(width 0.1)
				(type default)
			)
			(layer "F.Fab")
		)
		(fp_line
			(start 0.120396 0.3048)
			(end 0.120396 0.2794)
			(stroke
				(width 0.1)
				(type default)
			)
			(layer "F.Fab")
		)
		(fp_line
			(start 0.67945 0.3048)
			(end 0.120396 0.3048)
			(stroke
				(width 0.1)
				(type default)
			)
			(layer "F.Fab")
		)
		(fp_line
			(start -0.12065 0.2794)
			(end -0.12065 0.3048)
			(stroke
				(width 0.1)
				(type default)
			)
			(layer "F.Fab")
		)
		(fp_line
			(start 0.120396 0.2794)
			(end -0.12065 0.2794)
			(stroke
				(width 0.1)
				(type default)
			)
			(layer "F.Fab")
		)
		(fp_line
			(start -0.12065 -0.2794)
			(end 0.12065 -0.2794)
			(stroke
				(width 0.1)
				(type default)
			)
			(layer "F.Fab")
		)
		(fp_line
			(start 0.12065 -0.2794)
			(end 0.12065 -0.3048)
			(stroke
				(width 0.1)
				(type default)
			)
			(layer "F.Fab")
		)
		(fp_line
			(start 0.12065 -0.3048)
			(end 0.67945 -0.3048)
			(stroke
				(width 0.1)
				(type default)
			)
			(layer "F.Fab")
		)
		(fp_line
			(start 0.67945 -0.3048)
			(end 0.67945 0.3048)
			(stroke
				(width 0.1)
				(type default)
			)
			(layer "F.Fab")
		)
		(fp_line
			(start -0.67945 -0.305054)
			(end -0.12065 -0.305054)
			(stroke
				(width 0.1)
				(type default)
			)
			(layer "F.Fab")
		)
		(fp_line
			(start -0.12065 -0.305054)
			(end -0.12065 -0.2794)
			(stroke
				(width 0.1)
				(type default)
			)
			(layer "F.Fab")
		)
		(pad "1" smd circle
			(at -0.40005 0 270)
			(size 0 0)
			(layers "F.Cu" "F.Mask" "F.Paste")
			(net "NC_PVDD11_S3_P0_IMON3")
		)
		(pad "2" smd circle
			(at 0.40005 0 270)
			(size 0 0)
			(layers "F.Cu" "F.Mask" "F.Paste")
			(net "GND")
		)
	)
)
